# T6G (Grand Teton) — schematic netlist excerpt (pin names and nets, part order shuffled) for the footprints in the layout excerpt that follows; sources: Cadence DE-HDL packaged netlist, KiCad conversion of 04192023_DAF0TMB3IC0_F0TG_MB_C_brd_V02_OCP.brd

R1373  Q_RES  4.7K 5% CHIP  pkg 0201LF  page 331 : A = JTAG_TCK_RT_CPU1_P1 ; B = GND
C1064  Q_CAP  0.1UF 25V 10% X7R  pkg 0402  page 142 : A = P3V3_AUX ; B = GND
R125  Q_RES  0 5% CHIP  pkg 0402LF  page 238 : A = SMB_FRU_3V3AUX_SDA ; B = SMB_CPU_FRU_3V3AUX_SDA

(kicad_pcb
	(version 20260206)
	(generator "pcbnew")
	(generator_version "10.0")
	(general
		(thickness 1.6)
		(legacy_teardrops no)
	)
	(paper "A4")
	(title_block
		(title "04192023_DAF0TMB3IC0_F0TG_MB_C_brd_V02_OCP.brd")
		(comment 1 "Grand Teton / footprints 2607-2609 of 8354")
	)
	(layers
		(0 "F.Cu" signal "TOP")
		(4 "In1.Cu" signal "GND")
		(6 "In2.Cu" signal "IN1")
		(8 "In3.Cu" signal "GND1")
		(10 "In4.Cu" signal "IN2")
		(12 "In5.Cu" signal "GND2")
		(14 "In6.Cu" signal "IN3")
		(16 "In7.Cu" signal "GND3")
		(18 "In8.Cu" signal "VCC")
		(20 "In9.Cu" signal "VCC1")
		(22 "In10.Cu" signal "GND4")
		(24 "In11.Cu" signal "IN4")
		(26 "In12.Cu" signal "GND5")
		(28 "In13.Cu" signal "IN5")
		(30 "In14.Cu" signal "GND6")
		(32 "In15.Cu" signal "IN6")
		(34 "In16.Cu" signal "GND7")
		(2 "B.Cu" signal "BOTTOM")
		(9 "F.Adhes" user "F.Adhesive")
		(11 "B.Adhes" user "B.Adhesive")
		(13 "F.Paste" user "Package Geometry/Pastemask Top")
		(15 "B.Paste" user "Package Geometry/Pastemask Bottom")
		(5 "F.SilkS" user "Ref Des/Silkscreen Top")
		(7 "B.SilkS" user "Ref Des/Silkscreen Bottom")
		(1 "F.Mask" user "Board Geometry/Soldermask Top")
		(3 "B.Mask" user "Board Geometry/Soldermask Bottom")
		(17 "Dwgs.User" user "User.Drawings")
		(19 "Cmts.User" user "User.Comments")
		(21 "Eco1.User" user "User.Eco1")
		(23 "Eco2.User" user "User.Eco2")
		(25 "Edge.Cuts" user "Board Geometry/Outline")
		(27 "Margin" user)
		(31 "F.CrtYd" user "Package Geometry/Place Bound Top")
		(29 "B.CrtYd" user "Package Geometry/Place Bound Bottom")
		(35 "F.Fab" user "Ref Des/Assembly Top")
		(33 "B.Fab" user "Ref Des/Assembly Bottom")
	)
	(footprint ""
		(layer "F.Cu")
		(at 94.4626 -416.4076 180)
		(property "Reference" "R1373"
			(at 0 0 180)
			(layer "F.SilkS")
			(hide yes)
			(effects
				(font
					(size 1.27 1.27)
				)
			)
		)
		(property "Value" ""
			(at 0 0 180)
			(layer "F.Fab")
			(effects
				(font
					(size 1.27 1.27)
				)
			)
		)
		(duplicate_pad_numbers_are_jumpers no)
		(fp_line
			(start 0.32512 0.175006)
			(end -0.32512 0.175006)
			(stroke
				(width 0.1)
				(type default)
			)
			(layer "F.Fab")
		)
		(fp_line
			(start 0.32512 -0.175006)
			(end 0.32512 0.175006)
			(stroke
				(width 0.1)
				(type default)
			)
			(layer "F.Fab")
		)
		(fp_line
			(start -0.32512 0.175006)
			(end -0.32512 -0.175006)
			(stroke
				(width 0.1)
				(type default)
			)
			(layer "F.Fab")
		)
		(fp_line
			(start -0.32512 -0.175006)
			(end 0.32512 -0.175006)
			(stroke
				(width 0.1)
				(type default)
			)
			(layer "F.Fab")
		)
		(pad "1" smd rect
			(at -0.2667 0 180)
			(size 0.3048 0.381)
			(layers "F.Cu" "F.Mask" "F.Paste")
			(net "JTAG_TCK_RT_CPU1_P1")
		)
		(pad "2" smd rect
			(at 0.2667 0)
			(size 0.3048 0.381)
			(layers "F.Cu" "F.Mask" "F.Paste")
			(net "GND")
		)
	)
	(footprint ""
		(layer "F.Cu")
		(at 314.567316 -108.52277 180)
		(property "Reference" "R125"
			(at 0 0 180)
			(layer "F.SilkS")
			(hide yes)
			(effects
				(font
					(size 1.27 1.27)
				)
			)
		)
		(property "Value" ""
			(at 0 0 180)
			(layer "F.Fab")
			(effects
				(font
					(size 1.27 1.27)
				)
			)
		)
		(duplicate_pad_numbers_are_jumpers no)
		(fp_line
			(start 0.7874 0.4064)
			(end -0.7874 0.4064)
			(stroke
				(width 0.1524)
				(type default)
			)
			(layer "F.SilkS")
		)
		(fp_line
			(start 0.7874 -0.4064)
			(end 0.7874 0.4064)
			(stroke
				(width 0.1524)
				(type default)
			)
			(layer "F.SilkS")
		)
		(fp_line
			(start -0.7874 0.4064)
			(end -0.7874 -0.4064)
			(stroke
				(width 0.1524)
				(type default)
			)
			(layer "F.SilkS")
		)
		(fp_line
			(start -0.7874 -0.4064)
			(end 0.7874 -0.4064)
			(stroke
				(width 0.1524)
				(type default)
			)
			(layer "F.SilkS")
		)
		(fp_line
			(start 0.67945 0.3048)
			(end 0.120396 0.3048)
			(stroke
				(width 0.1)
				(type default)
			)
			(layer "F.Fab")
		)
		(fp_line
			(start 0.67945 -0.3048)
			(end 0.67945 0.3048)
			(stroke
				(width 0.1)
				(type default)
			)
			(layer "F.Fab")
		)
		(fp_line
			(start 0.12065 -0.2794)
			(end 0.12065 -0.3048)
			(stroke
				(width 0.1)
				(type default)
			)
			(layer "F.Fab")
		)
		(fp_line
			(start 0.12065 -0.3048)
			(end 0.67945 -0.3048)
			(stroke
				(width 0.1)
				(type default)
			)
			(layer "F.Fab")
		)
		(fp_line
			(start 0.120396 0.3048)
			(end 0.120396 0.2794)
			(stroke
				(width 0.1)
				(type default)
			)
			(layer "F.Fab")
		)
		(fp_line
			(start 0.120396 0.2794)
			(end -0.12065 0.2794)
			(stroke
				(width 0.1)
				(type default)
			)
			(layer "F.Fab")
		)
		(fp_line
			(start -0.12065 0.3048)
			(end -0.67945 0.3048)
			(stroke
				(width 0.1)
				(type default)
			)
			(layer "F.Fab")
		)
		(fp_line
			(start -0.12065 0.2794)
			(end -0.12065 0.3048)
			(stroke
				(width 0.1)
				(type default)
			)
			(layer "F.Fab")
		)
		(fp_line
			(start -0.12065 -0.2794)
			(end 0.12065 -0.2794)
			(stroke
				(width 0.1)
				(type default)
			)
			(layer "F.Fab")
		)
		(fp_line
			(start -0.12065 -0.305054)
			(end -0.12065 -0.2794)
			(stroke
				(width 0.1)
				(type default)
			)
			(layer "F.Fab")
		)
		(fp_line
			(start -0.67945 0.3048)
			(end -0.67945 -0.305054)
			(stroke
				(width 0.1)
				(type default)
			)
			(layer "F.Fab")
		)
		(fp_line
			(start -0.67945 -0.305054)
			(end -0.12065 -0.305054)
			(stroke
				(width 0.1)
				(type default)
			)
			(layer "F.Fab")
		)
		(pad "1" smd circle
			(at -0.40005 0 180)
			(size 0 0)
			(layers "F.Cu" "F.Mask" "F.Paste")
			(net "SMB_FRU_3V3AUX_SDA")
		)
		(pad "2" smd circle
			(at 0.40005 0 180)
			(size 0 0)
			(layers "F.Cu" "F.Mask" "F.Paste")
			(net "SMB_CPU_FRU_3V3AUX_SDA")
		)
	)
	(footprint ""
		(layer "F.Cu")
		(at 74.422 -56.134 -90)
		(property "Reference" "C1064"
			(at 0 0 270)
			(layer "F.SilkS")
			(hide yes)
			(effects
				(font
					(size 1.27 1.27)
				)
			)
		)
		(property "Value" ""
			(at 0 0 270)
			(layer "F.Fab")
			(effects
				(font
					(size 1.27 1.27)
				)
			)
		)
		(duplicate_pad_numbers_are_jumpers no)
		(fp_line
			(start -0.7874 0.4064)
			(end -0.7874 -0.4064)
			(stroke
				(width 0.1524)
				(type default)
			)
			(layer "F.SilkS")
		)
		(fp_line
			(start 0.7874 0.4064)
			(end -0.7874 0.4064)
			(stroke
				(width 0.1524)
				(type default)
			)
			(layer "F.SilkS")
		)
		(fp_line
			(start -0.7874 -0.4064)
			(end 0.7874 -0.4064)
			(stroke
				(width 0.1524)
				(type default)
			)
			(layer "F.SilkS")
		)
		(fp_line
			(start 0.7874 -0.4064)
			(end 0.7874 0.4064)
			(stroke
				(width 0.1524)
				(type default)
			)
			(layer "F.SilkS")
		)
		(fp_line
			(start -0.67945 0.3048)
			(end -0.67945 -0.305054)
			(stroke
				(width 0.1)
				(type default)
			)
			(layer "F.Fab")
		)
		(fp_line
			(start -0.12065 0.3048)
			(end -0.67945 0.3048)
			(stroke
				(width 0.1)
				(type default)
			)
			(layer "F.Fab")
		)
		(fp_line
			(start 0.120396 0.3048)
			(end 0.120396 0.2794)
			(stroke
				(width 0.1)
				(type default)
			)
			(layer "F.Fab")
		)
		(fp_line
			(start 0.67945 0.3048)
			(end 0.120396 0.3048)
			(stroke
				(width 0.1)
				(type default)
			)
			(layer "F.Fab")
		)
		(fp_line
			(start -0.12065 0.2794)
			(end -0.12065 0.3048)
			(stroke
				(width 0.1)
				(type default)
			)
			(layer "F.Fab")
		)
		(fp_line
			(start 0.120396 0.2794)
			(end -0.12065 0.2794)
			(stroke
				(width 0.1)
				(type default)
			)
			(layer "F.Fab")
		)
		(fp_line
			(start -0.12065 -0.2794)
			(end 0.12065 -0.2794)
			(stroke
				(width 0.1)
				(type default)
			)
			(layer "F.Fab")
		)
		(fp_line
			(start 0.12065 -0.2794)
			(end 0.12065 -0.3048)
			(stroke
				(width 0.1)
				(type default)
			)
			(layer "F.Fab")
		)
		(fp_line
			(start 0.12065 -0.3048)
			(end 0.67945 -0.3048)
			(stroke
				(width 0.1)
				(type default)
			)
			(layer "F.Fab")
		)
		(fp_line
			(start 0.67945 -0.3048)
			(end 0.67945 0.3048)
			(stroke
				(width 0.1)
				(type default)
			)
			(layer "F.Fab")
		)
		(fp_line
			(start -0.67945 -0.305054)
			(end -0.12065 -0.305054)
			(stroke
				(width 0.1)
				(type default)
			)
			(layer "F.Fab")
		)
		(fp_line
			(start -0.12065 -0.305054)
			(end -0.12065 -0.2794)
			(stroke
				(width 0.1)
				(type default)
			)
			(layer "F.Fab")
		)
		(pad "1" smd circle
			(at -0.40005 0 270)
			(size 0 0)
			(layers "F.Cu" "F.Mask" "F.Paste")
			(net "P3V3_AUX")
		)
		(pad "2" smd circle
			(at 0.40005 0 270)
			(size 0 0)
			(layers "F.Cu" "F.Mask" "F.Paste")
			(net "GND")
		)
	)
)
